(kicad_pcb
	(version 20260206)
	(generator "pcbnew")
	(generator_version "10.0")
	(general
		(thickness 1.6)
		(legacy_teardrops no)
	)
	(paper "A4")
	(title_block
		(title "04192023_DAF0TMB3IC0_F0TG_MB_C_brd_V02_OCP.brd")
		(comment 1 "Grand Teton / footprints 5637-5644 of 8354")
	)
	(layers
		(0 "F.Cu" signal "TOP")
		(4 "In1.Cu" signal "GND")
		(6 "In2.Cu" signal "IN1")
		(8 "In3.Cu" signal "GND1")
		(10 "In4.Cu" signal "IN2")
		(12 "In5.Cu" signal "GND2")
		(14 "In6.Cu" signal "IN3")
		(16 "In7.Cu" signal "GND3")
		(18 "In8.Cu" signal "VCC")
		(20 "In9.Cu" signal "VCC1")
		(22 "In10.Cu" signal "GND4")
		(24 "In11.Cu" signal "IN4")
		(26 "In12.Cu" signal "GND5")
		(28 "In13.Cu" signal "IN5")
		(30 "In14.Cu" signal "GND6")
		(32 "In15.Cu" signal "IN6")
		(34 "In16.Cu" signal "GND7")
		(2 "B.Cu" signal "BOTTOM")
		(9 "F.Adhes" user "F.Adhesive")
		(11 "B.Adhes" user "B.Adhesive")
		(13 "F.Paste" user "Package Geometry/Pastemask Top")
		(15 "B.Paste" user "Package Geometry/Pastemask Bottom")
		(5 "F.SilkS" user "Ref Des/Silkscreen Top")
		(7 "B.SilkS" user "Ref Des/Silkscreen Bottom")
		(1 "F.Mask" user "Board Geometry/Soldermask Top")
		(3 "B.Mask" user "Board Geometry/Soldermask Bottom")
		(17 "Dwgs.User" user "User.Drawings")
		(19 "Cmts.User" user "User.Comments")
		(21 "Eco1.User" user "User.Eco1")
		(23 "Eco2.User" user "User.Eco2")
		(25 "Edge.Cuts" user "Board Geometry/Outline")
		(27 "Margin" user)
		(31 "F.CrtYd" user "Package Geometry/Place Bound Top")
		(29 "B.CrtYd" user "Package Geometry/Place Bound Bottom")
		(35 "F.Fab" user "Ref Des/Assembly Top")
		(33 "B.Fab" user "Ref Des/Assembly Bottom")
	)
	(footprint ""
		(layer "B.Cu")
		(at 304.419 -358.14 180)
		(property "Reference" "R8066"
			(at 0 0 0)
			(layer "B.SilkS")
			(hide yes)
			(effects
				(font
					(size 1.27 1.27)
				)
				(justify mirror)
			)
		)
		(property "Value" ""
			(at 0 0 0)
			(layer "B.Fab")
			(effects
				(font
					(size 1.27 1.27)
				)
				(justify mirror)
			)
		)
		(duplicate_pad_numbers_are_jumpers no)
		(fp_line
			(start 0.7874 0.4064)
			(end 0.7874 -0.4064)
			(stroke
				(width 0.1524)
				(type default)
			)
			(layer "B.SilkS")
		)
		(fp_line
			(start 0.7874 -0.4064)
			(end -0.7874 -0.4064)
			(stroke
				(width 0.1524)
				(type default)
			)
			(layer "B.SilkS")
		)
		(fp_line
			(start -0.7874 0.4064)
			(end 0.7874 0.4064)
			(stroke
				(width 0.1524)
				(type default)
			)
			(layer "B.SilkS")
		)
		(fp_line
			(start -0.7874 -0.4064)
			(end -0.7874 0.4064)
			(stroke
				(width 0.1524)
				(type default)
			)
			(layer "B.SilkS")
		)
		(fp_line
			(start 0.67945 0.3048)
			(end 0.67945 -0.305054)
			(stroke
				(width 0.1)
				(type default)
			)
			(layer "B.Fab")
		)
		(fp_line
			(start 0.67945 -0.305054)
			(end 0.12065 -0.305054)
			(stroke
				(width 0.1)
				(type default)
			)
			(layer "B.Fab")
		)
		(fp_line
			(start 0.12065 0.3048)
			(end 0.67945 0.3048)
			(stroke
				(width 0.1)
				(type default)
			)
			(layer "B.Fab")
		)
		(fp_line
			(start 0.12065 0.2794)
			(end 0.12065 0.3048)
			(stroke
				(width 0.1)
				(type default)
			)
			(layer "B.Fab")
		)
		(fp_line
			(start 0.12065 -0.2794)
			(end -0.12065 -0.2794)
			(stroke
				(width 0.1)
				(type default)
			)
			(layer "B.Fab")
		)
		(fp_line
			(start 0.12065 -0.305054)
			(end 0.12065 -0.2794)
			(stroke
				(width 0.1)
				(type default)
			)
			(layer "B.Fab")
		)
		(fp_line
			(start -0.120396 0.3048)
			(end -0.120396 0.2794)
			(stroke
				(width 0.1)
				(type default)
			)
			(layer "B.Fab")
		)
		(fp_line
			(start -0.120396 0.2794)
			(end 0.12065 0.2794)
			(stroke
				(width 0.1)
				(type default)
			)
			(layer "B.Fab")
		)
		(fp_line
			(start -0.12065 -0.2794)
			(end -0.12065 -0.3048)
			(stroke
				(width 0.1)
				(type default)
			)
			(layer "B.Fab")
		)
		(fp_line
			(start -0.12065 -0.3048)
			(end -0.67945 -0.3048)
			(stroke
				(width 0.1)
				(type default)
			)
			(layer "B.Fab")
		)
		(fp_line
			(start -0.67945 0.3048)
			(end -0.120396 0.3048)
			(stroke
				(width 0.1)
				(type default)
			)
			(layer "B.Fab")
		)
		(fp_line
			(start -0.67945 -0.3048)
			(end -0.67945 0.3048)
			(stroke
				(width 0.1)
				(type default)
			)
			(layer "B.Fab")
		)
		(pad "1" smd circle
			(at 0.40005 0)
			(size 0 0)
			(layers "B.Cu" "B.Mask" "B.Paste")
			(net "PWRGD_PVDDIO_P0")
		)
		(pad "2" smd circle
			(at -0.40005 0)
			(size 0 0)
			(layers "B.Cu" "B.Mask" "B.Paste")
			(net "PWRGD_PVDDIO_P0_R")
		)
	)
	(footprint ""
		(layer "B.Cu")
		(at 324.390512 -336.047334 -90)
		(property "Reference" "PR80"
			(at 0 0 90)
			(layer "B.SilkS")
			(hide yes)
			(effects
				(font
					(size 1.27 1.27)
				)
				(justify mirror)
			)
		)
		(property "Value" ""
			(at 0 0 90)
			(layer "B.Fab")
			(effects
				(font
					(size 1.27 1.27)
				)
				(justify mirror)
			)
		)
		(duplicate_pad_numbers_are_jumpers no)
		(fp_line
			(start -0.7874 0.4064)
			(end 0.7874 0.4064)
			(stroke
				(width 0.1524)
				(type default)
			)
			(layer "B.SilkS")
		)
		(fp_line
			(start 0.7874 0.4064)
			(end 0.7874 -0.4064)
			(stroke
				(width 0.1524)
				(type default)
			)
			(layer "B.SilkS")
		)
		(fp_line
			(start -0.7874 -0.4064)
			(end -0.7874 0.4064)
			(stroke
				(width 0.1524)
				(type default)
			)
			(layer "B.SilkS")
		)
		(fp_line
			(start 0.7874 -0.4064)
			(end -0.7874 -0.4064)
			(stroke
				(width 0.1524)
				(type default)
			)
			(layer "B.SilkS")
		)
		(fp_line
			(start -0.67945 0.3048)
			(end -0.120396 0.3048)
			(stroke
				(width 0.1)
				(type default)
			)
			(layer "B.Fab")
		)
		(fp_line
			(start -0.120396 0.3048)
			(end -0.120396 0.2794)
			(stroke
				(width 0.1)
				(type default)
			)
			(layer "B.Fab")
		)
		(fp_line
			(start 0.12065 0.3048)
			(end 0.67945 0.3048)
			(stroke
				(width 0.1)
				(type default)
			)
			(layer "B.Fab")
		)
		(fp_line
			(start 0.67945 0.3048)
			(end 0.67945 -0.305054)
			(stroke
				(width 0.1)
				(type default)
			)
			(layer "B.Fab")
		)
		(fp_line
			(start -0.120396 0.2794)
			(end 0.12065 0.2794)
			(stroke
				(width 0.1)
				(type default)
			)
			(layer "B.Fab")
		)
		(fp_line
			(start 0.12065 0.2794)
			(end 0.12065 0.3048)
			(stroke
				(width 0.1)
				(type default)
			)
			(layer "B.Fab")
		)
		(fp_line
			(start -0.12065 -0.2794)
			(end -0.12065 -0.3048)
			(stroke
				(width 0.1)
				(type default)
			)
			(layer "B.Fab")
		)
		(fp_line
			(start 0.12065 -0.2794)
			(end -0.12065 -0.2794)
			(stroke
				(width 0.1)
				(type default)
			)
			(layer "B.Fab")
		)
		(fp_line
			(start -0.67945 -0.3048)
			(end -0.67945 0.3048)
			(stroke
				(width 0.1)
				(type default)
			)
			(layer "B.Fab")
		)
		(fp_line
			(start -0.12065 -0.3048)
			(end -0.67945 -0.3048)
			(stroke
				(width 0.1)
				(type default)
			)
			(layer "B.Fab")
		)
		(fp_line
			(start 0.12065 -0.305054)
			(end 0.12065 -0.2794)
			(stroke
				(width 0.1)
				(type default)
			)
			(layer "B.Fab")
		)
		(fp_line
			(start 0.67945 -0.305054)
			(end 0.12065 -0.305054)
			(stroke
				(width 0.1)
				(type default)
			)
			(layer "B.Fab")
		)
		(pad "1" smd circle
			(at 0.40005 0 90)
			(size 0 0)
			(layers "B.Cu" "B.Mask" "B.Paste")
			(net "PVDDCR_CPU1_P0_PVCC")
		)
		(pad "2" smd circle
			(at -0.40005 0 90)
			(size 0 0)
			(layers "B.Cu" "B.Mask" "B.Paste")
			(net "PVDDCR_CPU1_P0_VCC2")
		)
	)
	(footprint ""
		(layer "B.Cu")
		(at 49.401476 -337.985354 -90)
		(property "Reference" "PC456_1"
			(at 0 0 90)
			(layer "B.SilkS")
			(hide yes)
			(effects
				(font
					(size 1.27 1.27)
				)
				(justify mirror)
			)
		)
		(property "Value" ""
			(at 0 0 90)
			(layer "B.Fab")
			(effects
				(font
					(size 1.27 1.27)
				)
				(justify mirror)
			)
		)
		(duplicate_pad_numbers_are_jumpers no)
		(fp_line
			(start -1.524 0.762)
			(end 1.524 0.762)
			(stroke
				(width 0.1524)
				(type default)
			)
			(layer "B.SilkS")
		)
		(fp_line
			(start 1.524 0.762)
			(end 1.524 -0.762)
			(stroke
				(width 0.1524)
				(type default)
			)
			(layer "B.SilkS")
		)
		(fp_line
			(start -1.524 -0.762)
			(end -1.524 0.762)
			(stroke
				(width 0.1524)
				(type default)
			)
			(layer "B.SilkS")
		)
		(fp_line
			(start 1.524 -0.762)
			(end -1.524 -0.762)
			(stroke
				(width 0.1524)
				(type default)
			)
			(layer "B.SilkS")
		)
		(fp_line
			(start -1.1049 0.724916)
			(end -1.1049 -0.724916)
			(stroke
				(width 0.1)
				(type default)
			)
			(layer "B.Fab")
		)
		(fp_line
			(start 1.1049 0.724916)
			(end -1.1049 0.724916)
			(stroke
				(width 0.1)
				(type default)
			)
			(layer "B.Fab")
		)
		(fp_line
			(start -1.1049 -0.724916)
			(end 1.1049 -0.724916)
			(stroke
				(width 0.1)
				(type default)
			)
			(layer "B.Fab")
		)
		(fp_line
			(start 1.1049 -0.724916)
			(end 1.1049 0.724916)
			(stroke
				(width 0.1)
				(type default)
			)
			(layer "B.Fab")
		)
		(pad "1" smd rect
			(at 0.889 0 270)
			(size 1.016 1.27)
			(layers "B.Cu" "B.Mask" "B.Paste")
			(net "PVDDIO_P1")
		)
		(pad "2" smd rect
			(at -0.889 0 270)
			(size 1.016 1.27)
			(layers "B.Cu" "B.Mask" "B.Paste")
			(net "GND")
		)
	)
	(footprint ""
		(layer "B.Cu")
		(at 423.139616 -495.255042)
		(property "Reference" "LBL_2"
			(at 0 0 0)
			(layer "B.SilkS")
			(hide yes)
			(effects
				(font
					(size 1.27 1.27)
				)
				(justify mirror)
			)
		)
		(property "Value" ""
			(at 0 0 0)
			(layer "B.Fab")
			(effects
				(font
					(size 1.27 1.27)
				)
				(justify mirror)
			)
		)
		(duplicate_pad_numbers_are_jumpers no)
		(pad "1" smd circle
			(at 0 0 180)
			(size 0.762 0.762)
			(layers "B.Cu" "B.Mask" "B.Paste")
			(net "Net_10851")
		)
	)
	(footprint ""
		(layer "B.Cu")
		(at 225.679 -332.105)
		(property "Reference" "C7500"
			(at 0 0 0)
			(layer "B.SilkS")
			(hide yes)
			(effects
				(font
					(size 1.27 1.27)
				)
				(justify mirror)
			)
		)
		(property "Value" ""
			(at 0 0 0)
			(layer "B.Fab")
			(effects
				(font
					(size 1.27 1.27)
				)
				(justify mirror)
			)
		)
		(duplicate_pad_numbers_are_jumpers no)
		(fp_line
			(start -0.299974 -0.150114)
			(end -0.299974 0.150114)
			(stroke
				(width 0.1)
				(type default)
			)
			(layer "B.Fab")
		)
		(fp_line
			(start -0.299974 0.150114)
			(end 0.299974 0.150114)
			(stroke
				(width 0.1)
				(type default)
			)
			(layer "B.Fab")
		)
		(fp_line
			(start 0.299974 -0.150114)
			(end -0.299974 -0.150114)
			(stroke
				(width 0.1)
				(type default)
			)
			(layer "B.Fab")
		)
		(fp_line
			(start 0.299974 0.150114)
			(end 0.299974 -0.150114)
			(stroke
				(width 0.1)
				(type default)
			)
			(layer "B.Fab")
		)
		(pad "1" smd rect
			(at 0.2667 0 180)
			(size 0.3048 0.381)
			(layers "B.Cu" "B.Mask" "B.Paste")
			(net "P1V8_AUX")
		)
		(pad "2" smd rect
			(at -0.2667 0 180)
			(size 0.3048 0.381)
			(layers "B.Cu" "B.Mask" "B.Paste")
			(net "GND")
		)
	)
	(footprint ""
		(layer "B.Cu")
		(at 185.458608 -113.462816 90)
		(property "Reference" "C362"
			(at 0 0 90)
			(layer "B.SilkS")
			(hide yes)
			(effects
				(font
					(size 1.27 1.27)
				)
				(justify mirror)
			)
		)
		(property "Value" ""
			(at 0 0 90)
			(layer "B.Fab")
			(effects
				(font
					(size 1.27 1.27)
				)
				(justify mirror)
			)
		)
		(duplicate_pad_numbers_are_jumpers no)
		(fp_line
			(start 0.69215 -0.2921)
			(end -0.69215 -0.2921)
			(stroke
				(width 0.1524)
				(type default)
			)
			(layer "B.SilkS")
		)
		(fp_line
			(start -0.69215 -0.2921)
			(end -0.69215 0.2921)
			(stroke
				(width 0.1524)
				(type default)
			)
			(layer "B.SilkS")
		)
		(fp_line
			(start 0.69215 0.2921)
			(end 0.69215 -0.2921)
			(stroke
				(width 0.1524)
				(type default)
			)
			(layer "B.SilkS")
		)
		(fp_line
			(start -0.69215 0.2921)
			(end 0.69215 0.2921)
			(stroke
				(width 0.1524)
				(type default)
			)
			(layer "B.SilkS")
		)
		(fp_line
			(start 0.51435 -0.2794)
			(end -0.51435 -0.2794)
			(stroke
				(width 0.1)
				(type default)
			)
			(layer "B.Fab")
		)
		(fp_line
			(start -0.51435 -0.2794)
			(end -0.51435 0.2794)
			(stroke
				(width 0.1)
				(type default)
			)
			(layer "B.Fab")
		)
		(fp_line
			(start 0.51435 0.2794)
			(end 0.51435 -0.2794)
			(stroke
				(width 0.1)
				(type default)
			)
			(layer "B.Fab")
		)
		(fp_line
			(start -0.51435 0.2794)
			(end 0.51435 0.2794)
			(stroke
				(width 0.1)
				(type default)
			)
			(layer "B.Fab")
		)
		(pad "1" smd circle
			(at 0.40005 0 270)
			(size 0 0)
			(layers "B.Cu" "B.Mask" "B.Paste")
			(net "P3V3_AUX")
		)
		(pad "2" smd circle
			(at -0.40005 0 270)
			(size 0 0)
			(layers "B.Cu" "B.Mask" "B.Paste")
			(net "GND")
		)
		(zone
			(layer "B.Cu")
			(hatch none 0.5)
			(connect_pads
				(clearance 0)
			)
			(min_thickness 0.25)
			(keepout
				(tracks not_allowed)
				(vias allowed)
				(pads allowed)
				(copperpour not_allowed)
				(footprints allowed)
			)
			(placement
				(enabled no)
				(sheetname "")
			)
			(fill
				(thermal_gap 0.5)
				(thermal_bridge_width 0.5)
				(island_removal_mode 0)
			)
			(polygon
				(pts
					(xy 185.312558 -113.362486) (xy 185.312558 -113.561876) (xy 185.370724 -113.653316) (xy 185.546238 -113.653316)
					(xy 185.604404 -113.561876) (xy 185.604404 -113.362486) (xy 185.546238 -113.272316) (xy 185.370978 -113.272316)
				)
			)
		)
	)
	(footprint ""
		(layer "B.Cu")
		(at 340.705948 -395.148562 90)
		(property "Reference" "C621"
			(at 0 0 90)
			(layer "B.SilkS")
			(hide yes)
			(effects
				(font
					(size 1.27 1.27)
				)
				(justify mirror)
			)
		)
		(property "Value" ""
			(at 0 0 90)
			(layer "B.Fab")
			(effects
				(font
					(size 1.27 1.27)
				)
				(justify mirror)
			)
		)
		(duplicate_pad_numbers_are_jumpers no)
		(fp_line
			(start 0.299974 -0.150114)
			(end -0.299974 -0.150114)
			(stroke
				(width 0.1)
				(type default)
			)
			(layer "B.Fab")
		)
		(fp_line
			(start -0.299974 -0.150114)
			(end -0.299974 0.150114)
			(stroke
				(width 0.1)
				(type default)
			)
			(layer "B.Fab")
		)
		(fp_line
			(start 0.299974 0.150114)
			(end 0.299974 -0.150114)
			(stroke
				(width 0.1)
				(type default)
			)
			(layer "B.Fab")
		)
		(fp_line
			(start -0.299974 0.150114)
			(end 0.299974 0.150114)
			(stroke
				(width 0.1)
				(type default)
			)
			(layer "B.Fab")
		)
		(pad "1" smd rect
			(at 0.2667 0 270)
			(size 0.3048 0.381)
			(layers "B.Cu" "B.Mask" "B.Paste")
			(net "P0V9_CPU0_RT1_2A_2D")
		)
		(pad "2" smd rect
			(at -0.2667 0 270)
			(size 0.3048 0.381)
			(layers "B.Cu" "B.Mask" "B.Paste")
			(net "GND")
		)
	)
	(footprint ""
		(layer "B.Cu")
		(at 182.88254 -20.378166 90)
		(property "Reference" "R3239"
			(at 0 0 90)
			(layer "B.SilkS")
			(hide yes)
			(effects
				(font
					(size 1.27 1.27)
				)
				(justify mirror)
			)
		)
		(property "Value" ""
			(at 0 0 90)
			(layer "B.Fab")
			(effects
				(font
					(size 1.27 1.27)
				)
				(justify mirror)
			)
		)
		(duplicate_pad_numbers_are_jumpers no)
		(fp_line
			(start 0.7874 -0.4064)
			(end -0.7874 -0.4064)
			(stroke
				(width 0.1524)
				(type default)
			)
			(layer "B.SilkS")
		)
		(fp_line
			(start -0.7874 -0.4064)
			(end -0.7874 0.4064)
			(stroke
				(width 0.1524)
				(type default)
			)
			(layer "B.SilkS")
		)
		(fp_line
			(start 0.7874 0.4064)
			(end 0.7874 -0.4064)
			(stroke
				(width 0.1524)
				(type default)
			)
			(layer "B.SilkS")
		)
		(fp_line
			(start -0.7874 0.4064)
			(end 0.7874 0.4064)
			(stroke
				(width 0.1524)
				(type default)
			)
			(layer "B.SilkS")
		)
		(fp_line
			(start 0.67945 -0.305054)
			(end 0.12065 -0.305054)
			(stroke
				(width 0.1)
				(type default)
			)
			(layer "B.Fab")
		)
		(fp_line
			(start 0.12065 -0.305054)
			(end 0.12065 -0.2794)
			(stroke
				(width 0.1)
				(type default)
			)
			(layer "B.Fab")
		)
		(fp_line
			(start -0.12065 -0.3048)
			(end -0.67945 -0.3048)
			(stroke
				(width 0.1)
				(type default)
			)
			(layer "B.Fab")
		)
		(fp_line
			(start -0.67945 -0.3048)
			(end -0.67945 0.3048)
			(stroke
				(width 0.1)
				(type default)
			)
			(layer "B.Fab")
		)
		(fp_line
			(start 0.12065 -0.2794)
			(end -0.12065 -0.2794)
			(stroke
				(width 0.1)
				(type default)
			)
			(layer "B.Fab")
		)
		(fp_line
			(start -0.12065 -0.2794)
			(end -0.12065 -0.3048)
			(stroke
				(width 0.1)
				(type default)
			)
			(layer "B.Fab")
		)
		(fp_line
			(start 0.12065 0.2794)
			(end 0.12065 0.3048)
			(stroke
				(width 0.1)
				(type default)
			)
			(layer "B.Fab")
		)
		(fp_line
			(start -0.120396 0.2794)
			(end 0.12065 0.2794)
			(stroke
				(width 0.1)
				(type default)
			)
			(layer "B.Fab")
		)
		(fp_line
			(start 0.67945 0.3048)
			(end 0.67945 -0.305054)
			(stroke
				(width 0.1)
				(type default)
			)
			(layer "B.Fab")
		)
		(fp_line
			(start 0.12065 0.3048)
			(end 0.67945 0.3048)
			(stroke
				(width 0.1)
				(type default)
			)
			(layer "B.Fab")
		)
		(fp_line
			(start -0.120396 0.3048)
			(end -0.120396 0.2794)
			(stroke
				(width 0.1)
				(type default)
			)
			(layer "B.Fab")
		)
		(fp_line
			(start -0.67945 0.3048)
			(end -0.120396 0.3048)
			(stroke
				(width 0.1)
				(type default)
			)
			(layer "B.Fab")
		)
		(pad "1" smd circle
			(at 0.40005 0 270)
			(size 0 0)
			(layers "B.Cu" "B.Mask" "B.Paste")
			(net "SMB_OCP_SFF_3V3AUX_SDA")
		)
		(pad "2" smd circle
			(at -0.40005 0 270)
			(size 0 0)
			(layers "B.Cu" "B.Mask" "B.Paste")
			(net "SMB_OCP_SFF_3V3AUX_SDA_R0")
		)
	)
)
